(kicad_pcb
	(version 20260206)
	(generator "pcbnew")
	(generator_version "10.0")
	(general
		(thickness 1.6)
		(legacy_teardrops no)
	)
	(paper "A4")
	(title_block
		(title "v2-pdb — ms_pdb_v2.brd")
		(comment 1 "Open CloudServer (Microsoft) / footprints 226-235 of 348")
	)
	(layers
		(0 "F.Cu" signal "TOP")
		(4 "In1.Cu" signal "GND")
		(6 "In2.Cu" signal "IN1")
		(8 "In3.Cu" signal "VCC")
		(10 "In4.Cu" signal "VCC1")
		(12 "In5.Cu" signal "IN2")
		(14 "In6.Cu" signal "GND1")
		(2 "B.Cu" signal "BOTTOM")
		(9 "F.Adhes" user "F.Adhesive")
		(11 "B.Adhes" user "B.Adhesive")
		(13 "F.Paste" user "Package Geometry/Pastemask Top")
		(15 "B.Paste" user "Package Geometry/Pastemask Bottom")
		(5 "F.SilkS" user "Ref Des/Silkscreen Top")
		(7 "B.SilkS" user "Ref Des/Silkscreen Bottom")
		(1 "F.Mask" user "Board Geometry/Soldermask Top")
		(3 "B.Mask" user "Board Geometry/Soldermask Bottom")
		(17 "Dwgs.User" user "User.Drawings")
		(19 "Cmts.User" user "User.Comments")
		(21 "Eco1.User" user "User.Eco1")
		(23 "Eco2.User" user "User.Eco2")
		(25 "Edge.Cuts" user "Board Geometry/Outline")
		(27 "Margin" user)
		(31 "F.CrtYd" user "Package Geometry/Place Bound Top")
		(29 "B.CrtYd" user "Package Geometry/Place Bound Bottom")
		(35 "F.Fab" user "Ref Des/Assembly Top")
		(33 "B.Fab" user "Ref Des/Assembly Bottom")
	)
	(footprint ""
		(layer "F.Cu")
		(at 73.909936 -152.923748 -90)
		(property "Reference" "C23"
			(at -2.638552 0.124206 90)
			(unlocked yes)
			(layer "F.SilkS")
			(effects
				(font
					(size 0.7874 0.5842)
					(thickness 0.1524)
				)
				(justify left)
			)
		)
		(property "Value" ""
			(at 0 0 270)
			(layer "F.Fab")
			(effects
				(font
					(size 1.27 1.27)
				)
			)
		)
		(duplicate_pad_numbers_are_jumpers no)
		(fp_line
			(start -0.7874 0.4064)
			(end -0.7874 -0.4064)
			(stroke
				(width 0.1524)
				(type default)
			)
			(layer "F.SilkS")
		)
		(fp_line
			(start 0.7874 0.4064)
			(end -0.7874 0.4064)
			(stroke
				(width 0.1524)
				(type default)
			)
			(layer "F.SilkS")
		)
		(fp_line
			(start 0 0.381)
			(end 0 -0.381)
			(stroke
				(width 0.1524)
				(type default)
			)
			(layer "F.SilkS")
		)
		(fp_line
			(start -0.7874 -0.4064)
			(end 0.7874 -0.4064)
			(stroke
				(width 0.1524)
				(type default)
			)
			(layer "F.SilkS")
		)
		(fp_line
			(start 0.7874 -0.4064)
			(end 0.7874 0.4064)
			(stroke
				(width 0.1524)
				(type default)
			)
			(layer "F.SilkS")
		)
		(fp_poly
			(pts
				(xy -0.5334 0.254) (xy -0.635 0.254) (xy -0.635 0.2286) (xy -0.635 -0.254) (xy -0.5334 -0.254) (xy -0.5334 -0.2794)
				(xy 0.5334 -0.2794) (xy 0.5334 -0.254) (xy 0.635 -0.254) (xy 0.635 0.254) (xy 0.5334 0.254) (xy 0.5334 0.2794)
				(xy -0.508 0.2794) (xy -0.5334 0.2794)
			)
			(stroke
				(width 0)
				(type default)
			)
			(fill no)
			(layer "F.CrtYd")
		)
		(pad "1" smd rect
			(at 0.40005 0 270)
			(size 0.4572 0.508)
			(layers "F.Cu" "F.Mask" "F.Paste")
			(net "P12V")
		)
		(pad "2" smd rect
			(at -0.40005 0 270)
			(size 0.4572 0.508)
			(layers "F.Cu" "F.Mask" "F.Paste")
			(net "GND")
		)
	)
	(footprint ""
		(layer "F.Cu")
		(at 46.472856 -247.282716 180)
		(property "Reference" "R96"
			(at -0.980186 -0.54483 0)
			(unlocked yes)
			(layer "F.SilkS")
			(effects
				(font
					(size 0.7874 0.5842)
					(thickness 0.1524)
				)
				(justify left)
			)
		)
		(property "Value" ""
			(at 0 0 180)
			(layer "F.Fab")
			(effects
				(font
					(size 1.27 1.27)
				)
			)
		)
		(duplicate_pad_numbers_are_jumpers no)
		(fp_line
			(start 0.7874 0.4064)
			(end -0.7874 0.4064)
			(stroke
				(width 0.1524)
				(type default)
			)
			(layer "F.SilkS")
		)
		(fp_line
			(start 0.7874 -0.4064)
			(end 0.7874 0.4064)
			(stroke
				(width 0.1524)
				(type default)
			)
			(layer "F.SilkS")
		)
		(fp_line
			(start -0.7874 0.4064)
			(end -0.7874 -0.4064)
			(stroke
				(width 0.1524)
				(type default)
			)
			(layer "F.SilkS")
		)
		(fp_line
			(start -0.7874 -0.4064)
			(end 0.7874 -0.4064)
			(stroke
				(width 0.1524)
				(type default)
			)
			(layer "F.SilkS")
		)
		(fp_poly
			(pts
				(xy -0.508 0.2794) (xy -0.508 0.2286) (xy -0.635 0.2286) (xy -0.635 -0.254) (xy -0.5334 -0.254)
				(xy -0.5334 -0.2794) (xy 0.5334 -0.2794) (xy 0.5334 -0.254) (xy 0.635 -0.254) (xy 0.635 0.254) (xy 0.5334 0.254)
				(xy 0.5334 0.2794)
			)
			(stroke
				(width 0)
				(type default)
			)
			(fill no)
			(layer "F.CrtYd")
		)
		(pad "1" smd rect
			(at 0.40005 0 180)
			(size 0.4572 0.508)
			(layers "F.Cu" "F.Mask" "F.Paste")
			(net "PSU3_REMOTE_R_P")
		)
		(pad "2" smd rect
			(at -0.40005 0 180)
			(size 0.4572 0.508)
			(layers "F.Cu" "F.Mask" "F.Paste")
			(net "P12V")
		)
	)
	(footprint ""
		(layer "F.Cu")
		(at 70.236842 -38.821106 90)
		(property "Reference" "C11"
			(at 1.198626 -0.235712 90)
			(unlocked yes)
			(layer "F.SilkS")
			(effects
				(font
					(size 0.7874 0.5842)
					(thickness 0.1524)
				)
				(justify left)
			)
		)
		(property "Value" ""
			(at 0 0 90)
			(layer "F.Fab")
			(effects
				(font
					(size 1.27 1.27)
				)
			)
		)
		(duplicate_pad_numbers_are_jumpers no)
		(fp_line
			(start 0.7874 -0.4064)
			(end 0.7874 0.4064)
			(stroke
				(width 0.1524)
				(type default)
			)
			(layer "F.SilkS")
		)
		(fp_line
			(start -0.7874 -0.4064)
			(end 0.7874 -0.4064)
			(stroke
				(width 0.1524)
				(type default)
			)
			(layer "F.SilkS")
		)
		(fp_line
			(start 0 0.381)
			(end 0 -0.381)
			(stroke
				(width 0.1524)
				(type default)
			)
			(layer "F.SilkS")
		)
		(fp_line
			(start 0.7874 0.4064)
			(end -0.7874 0.4064)
			(stroke
				(width 0.1524)
				(type default)
			)
			(layer "F.SilkS")
		)
		(fp_line
			(start -0.7874 0.4064)
			(end -0.7874 -0.4064)
			(stroke
				(width 0.1524)
				(type default)
			)
			(layer "F.SilkS")
		)
		(fp_poly
			(pts
				(xy -0.5334 0.254) (xy -0.635 0.254) (xy -0.635 0.2286) (xy -0.635 -0.254) (xy -0.5334 -0.254) (xy -0.5334 -0.2794)
				(xy 0.5334 -0.2794) (xy 0.5334 -0.254) (xy 0.635 -0.254) (xy 0.635 0.254) (xy 0.5334 0.254) (xy 0.5334 0.2794)
				(xy -0.508 0.2794) (xy -0.5334 0.2794)
			)
			(stroke
				(width 0)
				(type default)
			)
			(fill no)
			(layer "F.CrtYd")
		)
		(pad "1" smd rect
			(at 0.40005 0 90)
			(size 0.4572 0.508)
			(layers "F.Cu" "F.Mask" "F.Paste")
			(net "P12V")
		)
		(pad "2" smd rect
			(at -0.40005 0 90)
			(size 0.4572 0.508)
			(layers "F.Cu" "F.Mask" "F.Paste")
			(net "GND")
		)
	)
	(footprint ""
		(layer "F.Cu")
		(at 73.512934 -419.288722 -90)
		(property "Reference" "C65"
			(at 3.469894 -0.070358 90)
			(unlocked yes)
			(layer "F.SilkS")
			(effects
				(font
					(size 0.7874 0.5842)
					(thickness 0.1524)
				)
				(justify left)
			)
		)
		(property "Value" ""
			(at 0 0 270)
			(layer "F.Fab")
			(effects
				(font
					(size 1.27 1.27)
				)
			)
		)
		(duplicate_pad_numbers_are_jumpers no)
		(fp_line
			(start -0.7874 0.4064)
			(end -0.7874 -0.4064)
			(stroke
				(width 0.1524)
				(type default)
			)
			(layer "F.SilkS")
		)
		(fp_line
			(start 0.7874 0.4064)
			(end -0.7874 0.4064)
			(stroke
				(width 0.1524)
				(type default)
			)
			(layer "F.SilkS")
		)
		(fp_line
			(start 0 0.381)
			(end 0 -0.381)
			(stroke
				(width 0.1524)
				(type default)
			)
			(layer "F.SilkS")
		)
		(fp_line
			(start -0.7874 -0.4064)
			(end 0.7874 -0.4064)
			(stroke
				(width 0.1524)
				(type default)
			)
			(layer "F.SilkS")
		)
		(fp_line
			(start 0.7874 -0.4064)
			(end 0.7874 0.4064)
			(stroke
				(width 0.1524)
				(type default)
			)
			(layer "F.SilkS")
		)
		(fp_poly
			(pts
				(xy -0.5334 0.254) (xy -0.635 0.254) (xy -0.635 0.2286) (xy -0.635 -0.254) (xy -0.5334 -0.254) (xy -0.5334 -0.2794)
				(xy 0.5334 -0.2794) (xy 0.5334 -0.254) (xy 0.635 -0.254) (xy 0.635 0.254) (xy 0.5334 0.254) (xy 0.5334 0.2794)
				(xy -0.508 0.2794) (xy -0.5334 0.2794)
			)
			(stroke
				(width 0)
				(type default)
			)
			(fill no)
			(layer "F.CrtYd")
		)
		(pad "1" smd rect
			(at 0.40005 0 270)
			(size 0.4572 0.508)
			(layers "F.Cu" "F.Mask" "F.Paste")
			(net "P12V")
		)
		(pad "2" smd rect
			(at -0.40005 0 270)
			(size 0.4572 0.508)
			(layers "F.Cu" "F.Mask" "F.Paste")
			(net "GND")
		)
	)
	(footprint ""
		(layer "F.Cu")
		(at 39.46398 -22.785324 -90)
		(property "Reference" "R86"
			(at -1.022858 -0.025146 90)
			(unlocked yes)
			(layer "F.SilkS")
			(effects
				(font
					(size 0.7874 0.5842)
					(thickness 0.1524)
				)
				(justify left)
			)
		)
		(property "Value" ""
			(at 0 0 270)
			(layer "F.Fab")
			(effects
				(font
					(size 1.27 1.27)
				)
			)
		)
		(duplicate_pad_numbers_are_jumpers no)
		(fp_line
			(start -0.7874 0.4064)
			(end -0.7874 -0.4064)
			(stroke
				(width 0.1524)
				(type default)
			)
			(layer "F.SilkS")
		)
		(fp_line
			(start 0.7874 0.4064)
			(end -0.7874 0.4064)
			(stroke
				(width 0.1524)
				(type default)
			)
			(layer "F.SilkS")
		)
		(fp_line
			(start -0.7874 -0.4064)
			(end 0.7874 -0.4064)
			(stroke
				(width 0.1524)
				(type default)
			)
			(layer "F.SilkS")
		)
		(fp_line
			(start 0.7874 -0.4064)
			(end 0.7874 0.4064)
			(stroke
				(width 0.1524)
				(type default)
			)
			(layer "F.SilkS")
		)
		(fp_poly
			(pts
				(xy -0.508 0.2794) (xy -0.508 0.2286) (xy -0.635 0.2286) (xy -0.635 -0.254) (xy -0.5334 -0.254)
				(xy -0.5334 -0.2794) (xy 0.5334 -0.2794) (xy 0.5334 -0.254) (xy 0.635 -0.254) (xy 0.635 0.254) (xy 0.5334 0.254)
				(xy 0.5334 0.2794)
			)
			(stroke
				(width 0)
				(type default)
			)
			(fill no)
			(layer "F.CrtYd")
		)
		(pad "1" smd rect
			(at 0.40005 0 270)
			(size 0.4572 0.508)
			(layers "F.Cu" "F.Mask" "F.Paste")
			(net "PSU1_REMOTE_P")
		)
		(pad "2" smd rect
			(at -0.40005 0 270)
			(size 0.4572 0.508)
			(layers "F.Cu" "F.Mask" "F.Paste")
			(net "PSU1_REMOTE_R_P")
		)
	)
	(footprint ""
		(layer "F.Cu")
		(at 27.052778 -10.617962)
		(property "Reference" "R50"
			(at -4.020312 -0.32258 0)
			(unlocked yes)
			(layer "F.SilkS")
			(effects
				(font
					(size 0.7874 0.5842)
					(thickness 0.1524)
				)
				(justify left)
			)
		)
		(property "Value" ""
			(at 0 0 0)
			(layer "F.Fab")
			(effects
				(font
					(size 1.27 1.27)
				)
			)
		)
		(duplicate_pad_numbers_are_jumpers no)
		(fp_line
			(start -0.7874 -0.4064)
			(end 0.7874 -0.4064)
			(stroke
				(width 0.1524)
				(type default)
			)
			(layer "F.SilkS")
		)
		(fp_line
			(start -0.7874 0.4064)
			(end -0.7874 -0.4064)
			(stroke
				(width 0.1524)
				(type default)
			)
			(layer "F.SilkS")
		)
		(fp_line
			(start 0.7874 -0.4064)
			(end 0.7874 0.4064)
			(stroke
				(width 0.1524)
				(type default)
			)
			(layer "F.SilkS")
		)
		(fp_line
			(start 0.7874 0.4064)
			(end -0.7874 0.4064)
			(stroke
				(width 0.1524)
				(type default)
			)
			(layer "F.SilkS")
		)
		(fp_poly
			(pts
				(xy -0.508 0.2794) (xy -0.508 0.2286) (xy -0.635 0.2286) (xy -0.635 -0.254) (xy -0.5334 -0.254)
				(xy -0.5334 -0.2794) (xy 0.5334 -0.2794) (xy 0.5334 -0.254) (xy 0.635 -0.254) (xy 0.635 0.254) (xy 0.5334 0.254)
				(xy 0.5334 0.2794)
			)
			(stroke
				(width 0)
				(type default)
			)
			(fill no)
			(layer "F.CrtYd")
		)
		(pad "1" smd rect
			(at 0.40005 0)
			(size 0.4572 0.508)
			(layers "F.Cu" "F.Mask" "F.Paste")
			(net "GND")
		)
		(pad "2" smd rect
			(at -0.40005 0)
			(size 0.4572 0.508)
			(layers "F.Cu" "F.Mask" "F.Paste")
			(net "PSU2_PS_ON_N")
		)
	)
	(footprint ""
		(layer "F.Cu")
		(at 74.69886 -419.288722 -90)
		(property "Reference" "C66"
			(at 3.469894 -0.070358 90)
			(unlocked yes)
			(layer "F.SilkS")
			(effects
				(font
					(size 0.7874 0.5842)
					(thickness 0.1524)
				)
				(justify left)
			)
		)
		(property "Value" ""
			(at 0 0 270)
			(layer "F.Fab")
			(effects
				(font
					(size 1.27 1.27)
				)
			)
		)
		(duplicate_pad_numbers_are_jumpers no)
		(fp_line
			(start -0.7874 0.4064)
			(end -0.7874 -0.4064)
			(stroke
				(width 0.1524)
				(type default)
			)
			(layer "F.SilkS")
		)
		(fp_line
			(start 0.7874 0.4064)
			(end -0.7874 0.4064)
			(stroke
				(width 0.1524)
				(type default)
			)
			(layer "F.SilkS")
		)
		(fp_line
			(start 0 0.381)
			(end 0 -0.381)
			(stroke
				(width 0.1524)
				(type default)
			)
			(layer "F.SilkS")
		)
		(fp_line
			(start -0.7874 -0.4064)
			(end 0.7874 -0.4064)
			(stroke
				(width 0.1524)
				(type default)
			)
			(layer "F.SilkS")
		)
		(fp_line
			(start 0.7874 -0.4064)
			(end 0.7874 0.4064)
			(stroke
				(width 0.1524)
				(type default)
			)
			(layer "F.SilkS")
		)
		(fp_poly
			(pts
				(xy -0.5334 0.254) (xy -0.635 0.254) (xy -0.635 0.2286) (xy -0.635 -0.254) (xy -0.5334 -0.254) (xy -0.5334 -0.2794)
				(xy 0.5334 -0.2794) (xy 0.5334 -0.254) (xy 0.635 -0.254) (xy 0.635 0.254) (xy 0.5334 0.254) (xy 0.5334 0.2794)
				(xy -0.508 0.2794) (xy -0.5334 0.2794)
			)
			(stroke
				(width 0)
				(type default)
			)
			(fill no)
			(layer "F.CrtYd")
		)
		(pad "1" smd rect
			(at 0.40005 0 270)
			(size 0.4572 0.508)
			(layers "F.Cu" "F.Mask" "F.Paste")
			(net "P12V")
		)
		(pad "2" smd rect
			(at -0.40005 0 270)
			(size 0.4572 0.508)
			(layers "F.Cu" "F.Mask" "F.Paste")
			(net "GND")
		)
	)
	(footprint ""
		(layer "F.Cu")
		(at 26.226008 -447.250058)
		(property "Reference" "R61"
			(at -1.712468 1.059942 0)
			(unlocked yes)
			(layer "F.SilkS")
			(effects
				(font
					(size 0.7874 0.5842)
					(thickness 0.1524)
				)
				(justify left)
			)
		)
		(property "Value" ""
			(at 0 0 0)
			(layer "F.Fab")
			(effects
				(font
					(size 1.27 1.27)
				)
			)
		)
		(duplicate_pad_numbers_are_jumpers no)
		(fp_line
			(start -0.7874 -0.4064)
			(end 0.7874 -0.4064)
			(stroke
				(width 0.1524)
				(type default)
			)
			(layer "F.SilkS")
		)
		(fp_line
			(start -0.7874 0.4064)
			(end -0.7874 -0.4064)
			(stroke
				(width 0.1524)
				(type default)
			)
			(layer "F.SilkS")
		)
		(fp_line
			(start 0.7874 -0.4064)
			(end 0.7874 0.4064)
			(stroke
				(width 0.1524)
				(type default)
			)
			(layer "F.SilkS")
		)
		(fp_line
			(start 0.7874 0.4064)
			(end -0.7874 0.4064)
			(stroke
				(width 0.1524)
				(type default)
			)
			(layer "F.SilkS")
		)
		(fp_poly
			(pts
				(xy -0.508 0.2794) (xy -0.508 0.2286) (xy -0.635 0.2286) (xy -0.635 -0.254) (xy -0.5334 -0.254)
				(xy -0.5334 -0.2794) (xy 0.5334 -0.2794) (xy 0.5334 -0.254) (xy 0.635 -0.254) (xy 0.635 0.254) (xy 0.5334 0.254)
				(xy 0.5334 0.2794)
			)
			(stroke
				(width 0)
				(type default)
			)
			(fill no)
			(layer "F.CrtYd")
		)
		(pad "1" smd rect
			(at 0.40005 0)
			(size 0.4572 0.508)
			(layers "F.Cu" "F.Mask" "F.Paste")
			(net "PSU6_RESET")
		)
		(pad "2" smd rect
			(at -0.40005 0)
			(size 0.4572 0.508)
			(layers "F.Cu" "F.Mask" "F.Paste")
			(net "GND")
		)
	)
	(footprint ""
		(layer "F.Cu")
		(at 50.150522 -128.655318 180)
		(property "Reference" "CE6"
			(at 0.794004 -5.521452 0)
			(unlocked yes)
			(layer "F.SilkS")
			(effects
				(font
					(size 0.7874 0.5842)
					(thickness 0.1524)
				)
				(justify left)
			)
		)
		(property "Value" ""
			(at 0 0 180)
			(layer "F.Fab")
			(effects
				(font
					(size 1.27 1.27)
				)
			)
		)
		(duplicate_pad_numbers_are_jumpers no)
		(fp_line
			(start 0 -4.2672)
			(end 0 4.2672)
			(stroke
				(width 0.1524)
				(type default)
			)
			(layer "F.SilkS")
		)
		(fp_circle
			(center 0 0)
			(end -4.2672 0)
			(stroke
				(width 0.1524)
				(type default)
			)
			(fill no)
			(layer "F.SilkS")
		)
		(fp_poly
			(pts
				(arc
					(start 0 -4.2672)
					(mid 4.2672 0)
					(end 0 4.2672)
				)
			)
			(stroke
				(width 0)
				(type default)
			)
			(fill yes)
			(layer "F.SilkS")
		)
		(fp_poly
			(pts
				(xy -2.5146 -0.762) (xy -0.9906 -0.762) (xy -0.9906 0.762) (xy -2.5146 0.762)
			)
			(stroke
				(width 0)
				(type default)
			)
			(fill no)
			(layer "B.CrtYd")
		)
		(fp_poly
			(pts
				(arc
					(start 1.7526 0.762)
					(mid 2.291415 -0.538815)
					(end 0.9906 0)
				)
				(arc
					(start 0.9906 0.0254)
					(mid 1.206345 0.546255)
					(end 1.7272 0.762)
				)
			)
			(stroke
				(width 0)
				(type default)
			)
			(fill no)
			(layer "B.CrtYd")
		)
		(fp_poly
			(pts
				(arc
					(start -4.2672 0)
					(mid 4.2672 0)
					(end -4.2672 0)
				)
			)
			(stroke
				(width 0)
				(type default)
			)
			(fill no)
			(layer "F.CrtYd")
		)
		(fp_circle
			(center 0 0)
			(end -4.2672 0)
			(stroke
				(width 0.1)
				(type default)
			)
			(fill no)
			(layer "F.Fab")
		)
		(fp_text user "+"
			(at -5.65785 -2.009648 180)
			(unlocked yes)
			(layer "F.SilkS")
			(effects
				(font
					(size 1.905 1.4224)
					(thickness 0.1524)
				)
				(justify left)
			)
		)
		(fp_text user "+"
			(at -5.6642 -0.34925 180)
			(unlocked yes)
			(layer "F.Fab")
			(effects
				(font
					(size 1.905 1.4224)
					(thickness 0.000001)
				)
				(justify left)
			)
		)
		(pad "1" thru_hole rect
			(at -1.75006 0 180)
			(size 1.397 1.397)
			(drill 0.9144)
			(layers "*.Cu" "*.Mask")
			(remove_unused_layers no)
			(net "P12V")
			(clearance 0.0127)
			(thermal_gap 0.0127)
			(padstack
				(mode front_inner_back)
				(layer "Inner"
					(shape circle)
					(size 1.397 1.397)
					(clearance 0.0127)
				)
				(layer "B.Cu"
					(shape rect)
					(size 1.397 1.397)
					(clearance 0.0127)
				)
			)
		)
		(pad "2" thru_hole circle
			(at 1.75006 0 180)
			(size 1.397 1.397)
			(drill 0.9144)
			(layers "*.Cu" "*.Mask")
			(remove_unused_layers no)
			(net "GND")
			(clearance 0.0127)
			(thermal_gap 0.0127)
		)
	)
	(footprint ""
		(layer "F.Cu")
		(at 20.408646 -446.145158 90)
		(property "Reference" "R155"
			(at -8.594852 1.446022 90)
			(unlocked yes)
			(layer "F.SilkS")
			(effects
				(font
					(size 0.7874 0.5842)
					(thickness 0.1524)
				)
				(justify left)
			)
		)
		(property "Value" ""
			(at 0 0 90)
			(layer "F.Fab")
			(effects
				(font
					(size 1.27 1.27)
				)
			)
		)
		(duplicate_pad_numbers_are_jumpers no)
		(fp_line
			(start 0.7874 -0.4064)
			(end 0.7874 0.4064)
			(stroke
				(width 0.1524)
				(type default)
			)
			(layer "F.SilkS")
		)
		(fp_line
			(start -0.7874 -0.4064)
			(end 0.7874 -0.4064)
			(stroke
				(width 0.1524)
				(type default)
			)
			(layer "F.SilkS")
		)
		(fp_line
			(start 0.7874 0.4064)
			(end -0.7874 0.4064)
			(stroke
				(width 0.1524)
				(type default)
			)
			(layer "F.SilkS")
		)
		(fp_line
			(start -0.7874 0.4064)
			(end -0.7874 -0.4064)
			(stroke
				(width 0.1524)
				(type default)
			)
			(layer "F.SilkS")
		)
		(fp_poly
			(pts
				(xy -0.508 0.2794) (xy -0.508 0.2286) (xy -0.635 0.2286) (xy -0.635 -0.254) (xy -0.5334 -0.254)
				(xy -0.5334 -0.2794) (xy 0.5334 -0.2794) (xy 0.5334 -0.254) (xy 0.635 -0.254) (xy 0.635 0.254) (xy 0.5334 0.254)
				(xy 0.5334 0.2794)
			)
			(stroke
				(width 0)
				(type default)
			)
			(fill no)
			(layer "F.CrtYd")
		)
		(pad "1" smd rect
			(at 0.40005 0 90)
			(size 0.4572 0.508)
			(layers "F.Cu" "F.Mask" "F.Paste")
			(net "P3V3_BUF")
		)
		(pad "2" smd rect
			(at -0.40005 0 90)
			(size 0.4572 0.508)
			(layers "F.Cu" "F.Mask" "F.Paste")
			(net "N42242336")
		)
	)
)
